# BASEBOARD_FAB2 (Tioga Pass) — schematic netlist excerpt (pin names and nets, part order shuffled) for the footprints in the layout excerpt that follows; sources: Cadence DE-HDL packaged netlist, KiCad conversion of Wiwynn_Tioga_Pass_MB.brd

R4B2  RES  120.0 1% CHIP  pkg 0603  page 234 : A = PVPP_KLM ; B = GND

Q8B1  MOSFET_N  BSZ019N03LS NFET  pkg LCC3  page 198
  SRC  = P5V
  GATE  = P5V_SWITCH_G
  DRN  = P5V_STBY

(kicad_pcb
	(version 20260206)
	(generator "pcbnew")
	(generator_version "10.0")
	(general
		(thickness 1.6)
		(legacy_teardrops no)
	)
	(paper "A4")
	(title_block
		(title "Wiwynn_Tioga_Pass_MB.brd")
		(comment 1 "Tioga Pass / footprints 1580-1581 of 4770")
	)
	(layers
		(0 "F.Cu" signal "TOP")
		(4 "In1.Cu" signal "L2GND")
		(6 "In2.Cu" signal "L3")
		(8 "In3.Cu" signal "L4GND")
		(10 "In4.Cu" signal "L5")
		(12 "In5.Cu" signal "L6GND")
		(14 "In6.Cu" signal "L7VCC")
		(16 "In7.Cu" signal "L8VCC")
		(18 "In8.Cu" signal "L9GND")
		(20 "In9.Cu" signal "L10")
		(22 "In10.Cu" signal "L11GND")
		(24 "In11.Cu" signal "L12")
		(26 "In12.Cu" signal "L13GND")
		(2 "B.Cu" signal "BOTTOM")
		(9 "F.Adhes" user "F.Adhesive")
		(11 "B.Adhes" user "B.Adhesive")
		(13 "F.Paste" user "Package Geometry/Pastemask Top")
		(15 "B.Paste" user "Package Geometry/Pastemask Bottom")
		(5 "F.SilkS" user "Ref Des/Silkscreen Top")
		(7 "B.SilkS" user "Ref Des/Silkscreen Bottom")
		(1 "F.Mask" user "Board Geometry/Soldermask Top")
		(3 "B.Mask" user "Board Geometry/Soldermask Bottom")
		(17 "Dwgs.User" user "User.Drawings")
		(19 "Cmts.User" user "User.Comments")
		(21 "Eco1.User" user "User.Eco1")
		(23 "Eco2.User" user "User.Eco2")
		(25 "Edge.Cuts" user "Board Geometry/Outline")
		(27 "Margin" user)
		(31 "F.CrtYd" user "Package Geometry/Place Bound Top")
		(29 "B.CrtYd" user "Package Geometry/Place Bound Bottom")
		(35 "F.Fab" user "Ref Des/Assembly Top")
		(33 "B.Fab" user "Ref Des/Assembly Bottom")
	)
	(footprint ""
		(layer "F.Cu")
		(at 169.0497 -132.5372)
		(property "Reference" "R4B2"
			(at 0 0 0)
			(layer "F.SilkS")
			(hide yes)
			(effects
				(font
					(size 1.27 1.27)
				)
			)
		)
		(property "Value" ""
			(at 0 0 0)
			(layer "F.Fab")
			(effects
				(font
					(size 1.27 1.27)
				)
			)
		)
		(duplicate_pad_numbers_are_jumpers no)
		(fp_poly
			(pts
				(xy -0.4953 -0.2032) (xy 0.4953 -0.2032) (xy 0.4953 1.6002) (xy -0.4953 1.6002)
			)
			(stroke
				(width 0)
				(type default)
			)
			(fill no)
			(layer "F.CrtYd")
		)
		(fp_line
			(start -0.4953 -0.2032)
			(end 0.4953 -0.2032)
			(stroke
				(width 0.1)
				(type default)
			)
			(layer "F.Fab")
		)
		(fp_line
			(start -0.4953 1.6002)
			(end -0.4953 -0.2032)
			(stroke
				(width 0.1)
				(type default)
			)
			(layer "F.Fab")
		)
		(fp_line
			(start 0.4953 -0.2032)
			(end 0.4953 1.6002)
			(stroke
				(width 0.1)
				(type default)
			)
			(layer "F.Fab")
		)
		(fp_line
			(start 0.4953 1.6002)
			(end -0.4953 1.6002)
			(stroke
				(width 0.1)
				(type default)
			)
			(layer "F.Fab")
		)
		(pad "1" smd rect
			(at 0 0)
			(size 0.762 0.889)
			(layers "F.Cu" "F.Mask" "F.Paste")
			(net "PVPP_KLM")
		)
		(pad "2" smd rect
			(at 0 1.397)
			(size 0.762 0.889)
			(layers "F.Cu" "F.Mask" "F.Paste")
			(net "GND")
		)
		(zone
			(layer "F.Cu")
			(hatch none 0.5)
			(connect_pads
				(clearance 0)
			)
			(min_thickness 0.25)
			(keepout
				(tracks not_allowed)
				(vias allowed)
				(pads allowed)
				(copperpour not_allowed)
				(footprints allowed)
			)
			(placement
				(enabled no)
				(sheetname "")
			)
			(fill
				(thermal_gap 0.5)
				(thermal_bridge_width 0.5)
				(island_removal_mode 0)
			)
			(polygon
				(pts
					(xy 168.6687 -131.5847) (xy 169.4307 -131.5847) (xy 169.4307 -132.0927) (xy 168.6687 -132.0927)
				)
			)
		)
		(zone
			(layer "F.Cu")
			(hatch none 0.5)
			(connect_pads
				(clearance 0)
			)
			(min_thickness 0.25)
			(keepout
				(tracks allowed)
				(vias not_allowed)
				(pads allowed)
				(copperpour not_allowed)
				(footprints allowed)
			)
			(placement
				(enabled no)
				(sheetname "")
			)
			(fill
				(thermal_gap 0.5)
				(thermal_bridge_width 0.5)
				(island_removal_mode 0)
			)
			(polygon
				(pts
					(xy 169.4307 -131.5847) (xy 169.4307 -132.0927) (xy 168.6687 -132.0927) (xy 168.6687 -131.5847)
				)
			)
		)
	)
	(footprint ""
		(layer "F.Cu")
		(at 436.753 -125.603 180)
		(property "Reference" "Q8B1"
			(at 3.36804 -2.27203 0)
			(unlocked yes)
			(layer "F.SilkS")
			(effects
				(font
					(size 0.7874 0.5842)
					(thickness 0.1524)
				)
				(justify left)
			)
		)
		(property "Value" ""
			(at 0 0 180)
			(layer "F.Fab")
			(effects
				(font
					(size 1.27 1.27)
				)
			)
		)
		(duplicate_pad_numbers_are_jumpers no)
		(fp_line
			(start -0.245364 2.020062)
			(end 3.15468 2.020062)
			(stroke
				(width 0.1524)
				(type default)
			)
			(layer "F.SilkS")
		)
		(fp_line
			(start -0.245364 -1.379982)
			(end 3.15468 -1.379982)
			(stroke
				(width 0.1524)
				(type default)
			)
			(layer "F.SilkS")
		)
		(fp_circle
			(center -0.94996 -1.512316)
			(end -1.07696 -1.512316)
			(stroke
				(width 0.254)
				(type default)
			)
			(fill no)
			(layer "F.SilkS")
		)
		(fp_poly
			(pts
				(xy 0.890016 -0.82296) (xy 0.890016 1.46304) (xy 3.404616 1.46304) (xy 3.404616 1.13284) (xy 2.617216 1.13284)
				(xy 2.617216 0.811022) (xy 3.404616 0.811022) (xy 3.404616 0.480822) (xy 2.617216 0.480822) (xy 2.617216 0.159258)
				(xy 3.404616 0.159258) (xy 3.404616 -0.170942) (xy 2.617216 -0.170942) (xy 2.617216 -0.49276) (xy 3.404616 -0.49276)
				(xy 3.404616 -0.82296)
			)
			(stroke
				(width 0)
				(type default)
			)
			(fill yes)
			(layer "F.Paste")
		)
		(fp_poly
			(pts
				(xy -0.245364 -1.379982) (xy -0.245364 2.020062) (xy 3.15468 2.020062) (xy 3.15468 -1.379982)
			)
			(stroke
				(width 0)
				(type default)
			)
			(fill no)
			(layer "F.CrtYd")
		)
		(fp_line
			(start 3.15468 2.020062)
			(end -0.245364 2.020062)
			(stroke
				(width 0.1)
				(type default)
			)
			(layer "F.Fab")
		)
		(fp_line
			(start 3.15468 -1.379982)
			(end 3.15468 2.020062)
			(stroke
				(width 0.1)
				(type default)
			)
			(layer "F.Fab")
		)
		(fp_line
			(start -0.245364 2.020062)
			(end -0.245364 -1.379982)
			(stroke
				(width 0.1)
				(type default)
			)
			(layer "F.Fab")
		)
		(fp_line
			(start -0.245364 -1.379982)
			(end 3.15468 -1.379982)
			(stroke
				(width 0.1)
				(type default)
			)
			(layer "F.Fab")
		)
		(fp_circle
			(center -0.94996 -1.512316)
			(end -1.07696 -1.512316)
			(stroke
				(width 0.254)
				(type default)
			)
			(fill no)
			(layer "F.Fab")
		)
		(pad "1" smd custom
			(at 0 0 180)
			(size 0.24765 0.24765)
			(layers "F.Cu" "F.Mask" "F.Paste")
			(net "P5V")
			(options
				(clearance outline)
				(anchor circle)
			)
			(primitives
				(gr_poly
					(pts
						(xy 0.4953 0.8255) (xy 0.4953 -0.8255) (xy -0.4953 -0.8255) (xy -0.4953 -0.4953) (xy 0.0127 -0.4953)
						(xy 0.0127 -0.1651) (xy -0.4953 -0.1651) (xy -0.4953 0.1651) (xy 0.0127 0.1651) (xy 0.0127 0.4953)
						(xy -0.4953 0.4953) (xy -0.4953 0.8255)
					)
					(width 0)
					(fill yes)
				)
			)
		)
		(pad "4" smd rect
			(at 0 1.30048 180)
			(size 0.9906 0.3302)
			(layers "F.Cu" "F.Mask" "F.Paste")
			(net "P5V_SWITCH_G")
		)
		(pad "5" smd custom
			(at 2.147316 0.32004 180)
			(size 0.5715 0.5715)
			(layers "F.Cu" "F.Mask" "F.Paste")
			(net "P5V_STBY")
			(options
				(clearance outline)
				(anchor circle)
			)
			(primitives
				(gr_poly
					(pts
						(xy -1.2573 -1.143) (xy -1.2573 1.143) (xy 1.2573 1.143) (xy 1.2573 0.8128) (xy 0.4699 0.8128)
						(xy 0.4699 0.490982) (xy 1.2573 0.490982) (xy 1.2573 0.160782) (xy 0.4699 0.160782) (xy 0.4699 -0.160782)
						(xy 1.2573 -0.160782) (xy 1.2573 -0.490982) (xy 0.4699 -0.490982) (xy 0.4699 -0.8128) (xy 1.2573 -0.8128)
						(xy 1.2573 -1.143)
					)
					(width 0)
					(fill yes)
				)
			)
		)
	)
)
